(kicad_pcb
	(version 20241229)
	(generator "pcbnew")
	(generator_version "9.0")
	(general
		(thickness 1.6642)
		(legacy_teardrops no)
	)
	(paper "A3")
	(title_block
		(title "PolarFire SoM")
		(date "2025-07-22")
		(rev "1.1.4")
		(company "Antmicro Ltd")
		(comment 1 "www.antmicro.com")
		(comment 9 "footprints 359-362 of 470")
	)
	(layers
		(0 "F.Cu" mixed)
		(4 "In1.Cu" power)
		(6 "In2.Cu" signal)
		(8 "In3.Cu" power)
		(10 "In4.Cu" signal)
		(12 "In5.Cu" power)
		(14 "In6.Cu" power)
		(16 "In7.Cu" signal)
		(18 "In8.Cu" power)
		(20 "In9.Cu" signal)
		(22 "In10.Cu" power)
		(24 "In11.Cu" signal)
		(26 "In12.Cu" signal)
		(2 "B.Cu" mixed)
		(9 "F.Adhes" user "F.Adhesive")
		(11 "B.Adhes" user "B.Adhesive")
		(13 "F.Paste" user)
		(15 "B.Paste" user)
		(5 "F.SilkS" user "F.Silkscreen")
		(7 "B.SilkS" user "B.Silkscreen")
		(1 "F.Mask" user)
		(3 "B.Mask" user)
		(17 "Dwgs.User" user "User.Drawings")
		(19 "Cmts.User" user "User.Comments")
		(21 "Eco1.User" user "User.Eco1")
		(23 "Eco2.User" user "User.Eco2")
		(25 "Edge.Cuts" user)
		(27 "Margin" user)
		(31 "F.CrtYd" user "F.Courtyard")
		(29 "B.CrtYd" user "B.Courtyard")
		(35 "F.Fab" user)
		(33 "B.Fab" user)
	)
	(footprint "antmicro-footprints:C_0402_1005Metric"
		(layer "B.Cu")
		(at 216.365 145.85)
		(descr "Capacitor SMD 0402")
		(tags "capacitor SMD 0402")
		(property "Reference" "C222"
			(at 0.145 4.46 0)
			(layer "B.SilkS")
			(effects
				(font
					(size 0.7 0.7)
					(thickness 0.15)
				)
				(justify right bottom mirror)
			)
		)
		(property "Value" "C_100n_0402"
			(at -1.022927 -2.155213 0)
			(layer "B.Fab")
			(hide yes)
			(effects
				(font
					(size 0.7 0.7)
					(thickness 0.15)
				)
				(justify right bottom mirror)
			)
		)
		(property "Datasheet" "https://www.murata.com/products/productdetail?partno=GRM155R61H104KE14%23"
			(at 0 0 0)
			(layer "F.Fab")
			(hide yes)
			(effects
				(font
					(size 1.27 1.27)
					(thickness 0.15)
				)
			)
		)
		(property "Description" "SMD Multilayer Ceramic Capacitor, 0.1 µF, 50 V, 0402 [1005 Metric], ± 10%, X5R, GRM Series"
			(at 0 0 0)
			(layer "F.Fab")
			(hide yes)
			(effects
				(font
					(size 1.27 1.27)
					(thickness 0.15)
				)
			)
		)
		(property "Author" "Antmicro"
			(at 0 0 0)
			(layer "B.Fab")
			(hide yes)
			(effects
				(font
					(size 1 1)
					(thickness 0.15)
				)
				(justify mirror)
			)
		)
		(property "Dielectric" "X5R"
			(at 0 0 0)
			(layer "B.Fab")
			(hide yes)
			(effects
				(font
					(size 1 1)
					(thickness 0.15)
				)
				(justify mirror)
			)
		)
		(property "License" "Apache-2.0"
			(at 0 0 0)
			(layer "B.Fab")
			(hide yes)
			(effects
				(font
					(size 1 1)
					(thickness 0.15)
				)
				(justify mirror)
			)
		)
		(property "MPN" "GRM155R61H104KE14D"
			(at 0 0 0)
			(layer "B.Fab")
			(hide yes)
			(effects
				(font
					(size 1 1)
					(thickness 0.15)
				)
				(justify mirror)
			)
		)
		(property "Manufacturer" "Murata"
			(at 0 0 0)
			(layer "B.Fab")
			(hide yes)
			(effects
				(font
					(size 1 1)
					(thickness 0.15)
				)
				(justify mirror)
			)
		)
		(property "Public" ""
			(at 0 0 0)
			(layer "B.Fab")
			(hide yes)
			(effects
				(font
					(size 1 1)
					(thickness 0.15)
				)
				(justify mirror)
			)
		)
		(property "Val" "100n"
			(at 0 0 0)
			(layer "B.Fab")
			(hide yes)
			(effects
				(font
					(size 1 1)
					(thickness 0.15)
				)
				(justify mirror)
			)
		)
		(property "Voltage" "50V"
			(at 0 0 0)
			(layer "B.Fab")
			(hide yes)
			(effects
				(font
					(size 1 1)
					(thickness 0.15)
				)
				(justify mirror)
			)
		)
		(sheetname "/USB/")
		(sheetfile "usb.kicad_sch")
		(attr smd)
		(fp_rect
			(start -0.925 0.47)
			(end 0.925 -0.47)
			(stroke
				(width 0.05)
				(type default)
			)
			(fill no)
			(layer "B.CrtYd")
		)
		(fp_line
			(start -0.494 -0.248)
			(end -0.494 0.25)
			(stroke
				(width 0.15)
				(type solid)
			)
			(layer "B.Fab")
		)
		(fp_line
			(start -0.494 0.25)
			(end 0.504 0.25)
			(stroke
				(width 0.15)
				(type solid)
			)
			(layer "B.Fab")
		)
		(fp_line
			(start 0.504 -0.248)
			(end -0.494 -0.248)
			(stroke
				(width 0.15)
				(type solid)
			)
			(layer "B.Fab")
		)
		(fp_line
			(start 0.504 0.25)
			(end 0.504 -0.248)
			(stroke
				(width 0.15)
				(type solid)
			)
			(layer "B.Fab")
		)
		(fp_text user "Author: Antmicro"
			(at -0.939 -3.399 180)
			(layer "B.Fab")
			(effects
				(font
					(size 0.7 0.7)
					(thickness 0.15)
				)
				(justify left bottom mirror)
			)
		)
		(fp_text user "${REFERENCE}"
			(at -0.939 -4.599 180)
			(layer "B.Fab")
			(effects
				(font
					(size 0.7 0.7)
					(thickness 0.15)
				)
				(justify left bottom mirror)
			)
		)
		(fp_text user "License: Apache-2.0"
			(at -0.939 -5.799 180)
			(layer "B.Fab")
			(effects
				(font
					(size 0.7 0.7)
					(thickness 0.15)
				)
				(justify left bottom mirror)
			)
		)
		(pad "1" smd roundrect
			(at -0.48 0)
			(size 0.59 0.64)
			(layers "B.Cu" "B.Mask" "B.Paste")
			(roundrect_rratio 0.25)
			(net 417 "GND")
			(pintype "passive")
		)
		(pad "2" smd roundrect
			(at 0.48 0)
			(size 0.59 0.64)
			(layers "B.Cu" "B.Mask" "B.Paste")
			(roundrect_rratio 0.25)
			(net 50 "+3V3")
			(pintype "passive")
		)
	)
	(footprint "antmicro-footprints:C_0402_1005Metric"
		(layer "B.Cu")
		(at 177.65 136.775)
		(descr "Capacitor SMD 0402")
		(tags "capacitor SMD 0402")
		(property "Reference" "C166"
			(at -1.06 -0.4 0)
			(layer "B.SilkS")
			(effects
				(font
					(size 0.7 0.7)
					(thickness 0.15)
				)
				(justify right bottom mirror)
			)
		)
		(property "Value" "C_1u_0402"
			(at -1.022927 -2.155213 0)
			(layer "B.Fab")
			(hide yes)
			(effects
				(font
					(size 0.7 0.7)
					(thickness 0.15)
				)
				(justify right bottom mirror)
			)
		)
		(property "Datasheet" "https://product.tdk.com/en/search/capacitor/ceramic/mlcc/info?part_no=C1005X6S1A105K050BC"
			(at 0 0 0)
			(layer "F.Fab")
			(hide yes)
			(effects
				(font
					(size 1.27 1.27)
					(thickness 0.15)
				)
			)
		)
		(property "Description" "SMD Multilayer Ceramic Capacitor, 1 µF, 10 V, 0402 [1005 Metric], ± 10%, X6S, C"
			(at 0 0 0)
			(layer "F.Fab")
			(hide yes)
			(effects
				(font
					(size 1.27 1.27)
					(thickness 0.15)
				)
			)
		)
		(property "Author" "Antmicro"
			(at 0 0 0)
			(layer "B.Fab")
			(hide yes)
			(effects
				(font
					(size 1 1)
					(thickness 0.15)
				)
				(justify mirror)
			)
		)
		(property "Dielectric" "X5R"
			(at 0 0 0)
			(layer "B.Fab")
			(hide yes)
			(effects
				(font
					(size 1 1)
					(thickness 0.15)
				)
				(justify mirror)
			)
		)
		(property "License" "Apache-2.0"
			(at 0 0 0)
			(layer "B.Fab")
			(hide yes)
			(effects
				(font
					(size 1 1)
					(thickness 0.15)
				)
				(justify mirror)
			)
		)
		(property "MPN" "C1005X6S1A105K050BC"
			(at 0 0 0)
			(layer "B.Fab")
			(hide yes)
			(effects
				(font
					(size 1 1)
					(thickness 0.15)
				)
				(justify mirror)
			)
		)
		(property "Manufacturer" "TDK"
			(at 0 0 0)
			(layer "B.Fab")
			(hide yes)
			(effects
				(font
					(size 1 1)
					(thickness 0.15)
				)
				(justify mirror)
			)
		)
		(property "Public" ""
			(at 0 0 0)
			(layer "B.Fab")
			(hide yes)
			(effects
				(font
					(size 1 1)
					(thickness 0.15)
				)
				(justify mirror)
			)
		)
		(property "Val" "1u"
			(at 0 0 0)
			(layer "B.Fab")
			(hide yes)
			(effects
				(font
					(size 1 1)
					(thickness 0.15)
				)
				(justify mirror)
			)
		)
		(property "Voltage" "16V"
			(at 0 0 0)
			(layer "B.Fab")
			(hide yes)
			(effects
				(font
					(size 1 1)
					(thickness 0.15)
				)
				(justify mirror)
			)
		)
		(sheetname "/LPDDR4/")
		(sheetfile "lpddr.kicad_sch")
		(attr smd)
		(fp_rect
			(start -0.925 0.47)
			(end 0.925 -0.47)
			(stroke
				(width 0.05)
				(type default)
			)
			(fill no)
			(layer "B.CrtYd")
		)
		(fp_line
			(start -0.494 -0.248)
			(end -0.494 0.25)
			(stroke
				(width 0.15)
				(type solid)
			)
			(layer "B.Fab")
		)
		(fp_line
			(start -0.494 0.25)
			(end 0.504 0.25)
			(stroke
				(width 0.15)
				(type solid)
			)
			(layer "B.Fab")
		)
		(fp_line
			(start 0.504 -0.248)
			(end -0.494 -0.248)
			(stroke
				(width 0.15)
				(type solid)
			)
			(layer "B.Fab")
		)
		(fp_line
			(start 0.504 0.25)
			(end 0.504 -0.248)
			(stroke
				(width 0.15)
				(type solid)
			)
			(layer "B.Fab")
		)
		(fp_text user "License: Apache-2.0"
			(at -0.939 -5.799 180)
			(layer "B.Fab")
			(effects
				(font
					(size 0.7 0.7)
					(thickness 0.15)
				)
				(justify left bottom mirror)
			)
		)
		(fp_text user "${REFERENCE}"
			(at -0.939 -4.599 180)
			(layer "B.Fab")
			(effects
				(font
					(size 0.7 0.7)
					(thickness 0.15)
				)
				(justify left bottom mirror)
			)
		)
		(fp_text user "Author: Antmicro"
			(at -0.939 -3.399 180)
			(layer "B.Fab")
			(effects
				(font
					(size 0.7 0.7)
					(thickness 0.15)
				)
				(justify left bottom mirror)
			)
		)
		(pad "1" smd roundrect
			(at -0.48 0)
			(size 0.59 0.64)
			(layers "B.Cu" "B.Mask" "B.Paste")
			(roundrect_rratio 0.25)
			(net 417 "GND")
			(pintype "passive")
		)
		(pad "2" smd roundrect
			(at 0.48 0)
			(size 0.59 0.64)
			(layers "B.Cu" "B.Mask" "B.Paste")
			(roundrect_rratio 0.25)
			(net 2 "+1V1")
			(pintype "passive")
		)
	)
	(footprint "antmicro-footprints:R_0603_1608Metric"
		(layer "B.Cu")
		(at 176.61 144.7 -90)
		(descr "Resistor SMD 0603")
		(tags "resistor SMD 0603")
		(property "Reference" "R48"
			(at -2.14 -1.54 270)
			(layer "B.SilkS")
			(effects
				(font
					(size 0.7 0.7)
					(thickness 0.15)
				)
				(justify left bottom mirror)
			)
		)
		(property "Value" "R_0R01_0603"
			(at 0 -1.6 90)
			(layer "B.Fab")
			(hide yes)
			(effects
				(font
					(size 0.7 0.7)
					(thickness 0.15)
				)
				(justify left bottom mirror)
			)
		)
		(property "Datasheet" "https://www.bourns.com/docs/product-datasheets/cfn-a.pdf"
			(at 0 0 270)
			(layer "F.Fab")
			(hide yes)
			(effects
				(font
					(size 1.27 1.27)
					(thickness 0.15)
				)
			)
		)
		(property "Description" "SMD Chip Resistor, 10 mohm, ± 1%, 0.5 W, 0603 [1608 Metric], Metal Foil, Current Sensing"
			(at 0 0 270)
			(layer "F.Fab")
			(hide yes)
			(effects
				(font
					(size 1.27 1.27)
					(thickness 0.15)
				)
			)
		)
		(property "Author" "Antmicro"
			(at 31.91 321.31 0)
			(layer "B.Fab")
			(hide yes)
			(effects
				(font
					(size 1 1)
					(thickness 0.15)
				)
				(justify mirror)
			)
		)
		(property "License" "Apache-2.0"
			(at 31.91 321.31 0)
			(layer "B.Fab")
			(hide yes)
			(effects
				(font
					(size 1 1)
					(thickness 0.15)
				)
				(justify mirror)
			)
		)
		(property "MPN" "CFN0603AFZ-R010ELF"
			(at 31.91 321.31 0)
			(layer "B.Fab")
			(hide yes)
			(effects
				(font
					(size 1 1)
					(thickness 0.15)
				)
				(justify mirror)
			)
		)
		(property "Manufacturer" "Bourns"
			(at 31.91 321.31 0)
			(layer "B.Fab")
			(hide yes)
			(effects
				(font
					(size 1 1)
					(thickness 0.15)
				)
				(justify mirror)
			)
		)
		(property "Public" ""
			(at 31.91 321.31 0)
			(layer "B.Fab")
			(hide yes)
			(effects
				(font
					(size 1 1)
					(thickness 0.15)
				)
				(justify mirror)
			)
		)
		(property "Tolerance" "1%"
			(at 31.91 321.31 0)
			(layer "B.Fab")
			(hide yes)
			(effects
				(font
					(size 1 1)
					(thickness 0.15)
				)
				(justify mirror)
			)
		)
		(property "Val" "0R01"
			(at 31.91 321.31 0)
			(layer "B.Fab")
			(hide yes)
			(effects
				(font
					(size 1 1)
					(thickness 0.15)
				)
				(justify mirror)
			)
		)
		(sheetname "/Supply/")
		(sheetfile "supply.kicad_sch")
		(attr smd)
		(fp_line
			(start -0.15 0.4)
			(end 0.15 0.4)
			(stroke
				(width 0.15)
				(type solid)
			)
			(layer "B.SilkS")
		)
		(fp_line
			(start -0.15 -0.4)
			(end 0.15 -0.4)
			(stroke
				(width 0.15)
				(type solid)
			)
			(layer "B.SilkS")
		)
		(fp_rect
			(start -1.25 0.65)
			(end 1.25 -0.65)
			(stroke
				(width 0.05)
				(type solid)
			)
			(fill no)
			(layer "B.CrtYd")
		)
		(fp_rect
			(start -0.8 0.4)
			(end 0.8 -0.4)
			(stroke
				(width 0.15)
				(type solid)
			)
			(fill no)
			(layer "B.Fab")
		)
		(fp_text user "Author: Antmicro"
			(at -1.25 -4.9 90)
			(layer "B.Fab")
			(effects
				(font
					(size 0.7 0.7)
					(thickness 0.15)
				)
				(justify left bottom mirror)
			)
		)
		(fp_text user "License: Apache-2.0"
			(at -1.25 -5.9 90)
			(layer "B.Fab")
			(effects
				(font
					(size 0.7 0.7)
					(thickness 0.15)
				)
				(justify left bottom mirror)
			)
		)
		(fp_text user "${REFERENCE}"
			(at -1.25 -3.898 90)
			(layer "B.Fab")
			(effects
				(font
					(size 0.7 0.7)
					(thickness 0.15)
				)
				(justify left bottom mirror)
			)
		)
		(pad "1" smd roundrect
			(at -0.7 0 270)
			(size 0.8 1)
			(layers "B.Cu" "B.Mask" "B.Paste")
			(roundrect_rratio 0.2)
			(net 406 "/Supply/SENSE2_P")
			(pintype "passive")
		)
		(pad "2" smd roundrect
			(at 0.7 0 270)
			(size 0.8 1)
			(layers "B.Cu" "B.Mask" "B.Paste")
			(roundrect_rratio 0.2)
			(net 48 "+1V8")
			(pintype "passive")
		)
	)
	(footprint "antmicro-footprints:C_0402_1005Metric"
		(layer "B.Cu")
		(at 213.861 121.754 180)
		(descr "Capacitor SMD 0402")
		(tags "capacitor SMD 0402")
		(property "Reference" "C252"
			(at -15.364 -13.121 0)
			(layer "B.SilkS")
			(effects
				(font
					(size 0.7 0.7)
					(thickness 0.15)
				)
				(justify left bottom mirror)
			)
		)
		(property "Value" "C_100n_0402"
			(at -1.022927 -2.155213 0)
			(layer "B.Fab")
			(hide yes)
			(effects
				(font
					(size 0.7 0.7)
					(thickness 0.15)
				)
				(justify left bottom mirror)
			)
		)
		(property "Datasheet" "https://www.murata.com/products/productdetail?partno=GRM155R61H104KE14%23"
			(at 0 0 180)
			(layer "F.Fab")
			(hide yes)
			(effects
				(font
					(size 1.27 1.27)
					(thickness 0.15)
				)
			)
		)
		(property "Description" "SMD Multilayer Ceramic Capacitor, 0.1 µF, 50 V, 0402 [1005 Metric], ± 10%, X5R, GRM Series"
			(at 0 0 180)
			(layer "F.Fab")
			(hide yes)
			(effects
				(font
					(size 1.27 1.27)
					(thickness 0.15)
				)
			)
		)
		(property "Author" "Antmicro"
			(at 427.722 243.508 0)
			(layer "B.Fab")
			(hide yes)
			(effects
				(font
					(size 1 1)
					(thickness 0.15)
				)
				(justify mirror)
			)
		)
		(property "Dielectric" "X5R"
			(at 427.722 243.508 0)
			(layer "B.Fab")
			(hide yes)
			(effects
				(font
					(size 1 1)
					(thickness 0.15)
				)
				(justify mirror)
			)
		)
		(property "License" "Apache-2.0"
			(at 427.722 243.508 0)
			(layer "B.Fab")
			(hide yes)
			(effects
				(font
					(size 1 1)
					(thickness 0.15)
				)
				(justify mirror)
			)
		)
		(property "MPN" "GRM155R61H104KE14D"
			(at 427.722 243.508 0)
			(layer "B.Fab")
			(hide yes)
			(effects
				(font
					(size 1 1)
					(thickness 0.15)
				)
				(justify mirror)
			)
		)
		(property "Manufacturer" "Murata"
			(at 427.722 243.508 0)
			(layer "B.Fab")
			(hide yes)
			(effects
				(font
					(size 1 1)
					(thickness 0.15)
				)
				(justify mirror)
			)
		)
		(property "Public" ""
			(at 427.722 243.508 0)
			(layer "B.Fab")
			(hide yes)
			(effects
				(font
					(size 1 1)
					(thickness 0.15)
				)
				(justify mirror)
			)
		)
		(property "Val" "100n"
			(at 427.722 243.508 0)
			(layer "B.Fab")
			(hide yes)
			(effects
				(font
					(size 1 1)
					(thickness 0.15)
				)
				(justify mirror)
			)
		)
		(property "Voltage" "50V"
			(at 427.722 243.508 0)
			(layer "B.Fab")
			(hide yes)
			(effects
				(font
					(size 1 1)
					(thickness 0.15)
				)
				(justify mirror)
			)
		)
		(sheetname "/Ethernet/")
		(sheetfile "ethernet.kicad_sch")
		(attr smd)
		(fp_rect
			(start -0.925 0.47)
			(end 0.925 -0.47)
			(stroke
				(width 0.05)
				(type default)
			)
			(fill no)
			(layer "B.CrtYd")
		)
		(fp_line
			(start 0.504 0.25)
			(end 0.504 -0.248)
			(stroke
				(width 0.15)
				(type solid)
			)
			(layer "B.Fab")
		)
		(fp_line
			(start 0.504 -0.248)
			(end -0.494 -0.248)
			(stroke
				(width 0.15)
				(type solid)
			)
			(layer "B.Fab")
		)
		(fp_line
			(start -0.494 0.25)
			(end 0.504 0.25)
			(stroke
				(width 0.15)
				(type solid)
			)
			(layer "B.Fab")
		)
		(fp_line
			(start -0.494 -0.248)
			(end -0.494 0.25)
			(stroke
				(width 0.15)
				(type solid)
			)
			(layer "B.Fab")
		)
		(fp_text user "Author: Antmicro"
			(at -0.939 -3.399 0)
			(layer "B.Fab")
			(effects
				(font
					(size 0.7 0.7)
					(thickness 0.15)
				)
				(justify left bottom mirror)
			)
		)
		(fp_text user "${REFERENCE}"
			(at -0.939 -4.599 0)
			(layer "B.Fab")
			(effects
				(font
					(size 0.7 0.7)
					(thickness 0.15)
				)
				(justify left bottom mirror)
			)
		)
		(fp_text user "License: Apache-2.0"
			(at -0.939 -5.799 0)
			(layer "B.Fab")
			(effects
				(font
					(size 0.7 0.7)
					(thickness 0.15)
				)
				(justify left bottom mirror)
			)
		)
		(pad "1" smd roundrect
			(at -0.48 0 180)
			(size 0.59 0.64)
			(layers "B.Cu" "B.Mask" "B.Paste")
			(roundrect_rratio 0.25)
			(net 417 "GND")
			(pintype "passive")
		)
		(pad "2" smd roundrect
			(at 0.48 0 180)
			(size 0.59 0.64)
			(layers "B.Cu" "B.Mask" "B.Paste")
			(roundrect_rratio 0.25)
			(net 47 "+1V05")
			(pintype "passive")
		)
	)
)
